# BASEBOARD_FAB2 (Tioga Pass) — schematic netlist excerpt (pin names and nets, part order shuffled) for the footprints in the layout excerpt that follows; sources: Cadence DE-HDL packaged netlist, KiCad conversion of Wiwynn_Tioga_Pass_MB.brd

C2L22  CAP_A  0.01UF 25V 10% X7R  pkg 0402V  page 173 : A = SATA6G_P3_TX_C_DN ; B = SATA6G_PCH_PCIE_UP_SATA_TXN<3>
C9W14  CAP  10UF 6.3V 20% X6S  pkg 0603  page 238 : A = P3V3_STBY ; B = GND
C6L11  CAP  1.0UF 16V 10% X6S  pkg 0402  page 234 : A = VR_FET_SW_P12V_STBY_PVPP_KLM ; B = GND

(kicad_pcb
	(version 20260206)
	(generator "pcbnew")
	(generator_version "10.0")
	(general
		(thickness 1.6)
		(legacy_teardrops no)
	)
	(paper "A4")
	(title_block
		(title "Wiwynn_Tioga_Pass_MB.brd")
		(comment 1 "Tioga Pass / footprints 4757-4759 of 4770")
	)
	(layers
		(0 "F.Cu" signal "TOP")
		(4 "In1.Cu" signal "L2GND")
		(6 "In2.Cu" signal "L3")
		(8 "In3.Cu" signal "L4GND")
		(10 "In4.Cu" signal "L5")
		(12 "In5.Cu" signal "L6GND")
		(14 "In6.Cu" signal "L7VCC")
		(16 "In7.Cu" signal "L8VCC")
		(18 "In8.Cu" signal "L9GND")
		(20 "In9.Cu" signal "L10")
		(22 "In10.Cu" signal "L11GND")
		(24 "In11.Cu" signal "L12")
		(26 "In12.Cu" signal "L13GND")
		(2 "B.Cu" signal "BOTTOM")
		(9 "F.Adhes" user "F.Adhesive")
		(11 "B.Adhes" user "B.Adhesive")
		(13 "F.Paste" user "Package Geometry/Pastemask Top")
		(15 "B.Paste" user "Package Geometry/Pastemask Bottom")
		(5 "F.SilkS" user "Ref Des/Silkscreen Top")
		(7 "B.SilkS" user "Ref Des/Silkscreen Bottom")
		(1 "F.Mask" user "Board Geometry/Soldermask Top")
		(3 "B.Mask" user "Board Geometry/Soldermask Bottom")
		(17 "Dwgs.User" user "User.Drawings")
		(19 "Cmts.User" user "User.Comments")
		(21 "Eco1.User" user "User.Eco1")
		(23 "Eco2.User" user "User.Eco2")
		(25 "Edge.Cuts" user "Board Geometry/Outline")
		(27 "Margin" user)
		(31 "F.CrtYd" user "Package Geometry/Place Bound Top")
		(29 "B.CrtYd" user "Package Geometry/Place Bound Bottom")
		(35 "F.Fab" user "Ref Des/Assembly Top")
		(33 "B.Fab" user "Ref Des/Assembly Bottom")
	)
	(footprint ""
		(layer "B.Cu")
		(at 421.513 -147.828 -90)
		(property "Reference" "C2L22"
			(at 0 0 90)
			(layer "B.SilkS")
			(hide yes)
			(effects
				(font
					(size 1.27 1.27)
				)
				(justify mirror)
			)
		)
		(property "Value" ""
			(at 0 0 90)
			(layer "B.Fab")
			(effects
				(font
					(size 1.27 1.27)
				)
				(justify mirror)
			)
		)
		(duplicate_pad_numbers_are_jumpers no)
		(fp_poly
			(pts
				(xy -0.3048 -0.1016) (xy -0.3048 0.9906) (xy 0.3048 0.9906) (xy 0.3048 -0.1016)
			)
			(stroke
				(width 0)
				(type default)
			)
			(fill no)
			(layer "B.CrtYd")
		)
		(fp_line
			(start -0.3048 0.9906)
			(end -0.3048 -0.1016)
			(stroke
				(width 0.1)
				(type default)
			)
			(layer "B.Fab")
		)
		(fp_line
			(start 0.3048 0.9906)
			(end -0.3048 0.9906)
			(stroke
				(width 0.1)
				(type default)
			)
			(layer "B.Fab")
		)
		(fp_line
			(start -0.3048 -0.1016)
			(end 0.3048 -0.1016)
			(stroke
				(width 0.1)
				(type default)
			)
			(layer "B.Fab")
		)
		(fp_line
			(start 0.3048 -0.1016)
			(end 0.3048 0.9906)
			(stroke
				(width 0.1)
				(type default)
			)
			(layer "B.Fab")
		)
		(pad "1" smd rect
			(at 0 0 90)
			(size 0.508 0.508)
			(layers "B.Cu" "B.Mask" "B.Paste")
			(net "SATA6G_P3_TX_C_DN")
		)
		(pad "2" smd rect
			(at 0 0.889 90)
			(size 0.508 0.508)
			(layers "B.Cu" "B.Mask" "B.Paste")
			(net "SATA6G_PCH_PCIE_UP_SATA_TXN<3>")
		)
		(zone
			(layer "B.Cu")
			(hatch none 0.5)
			(connect_pads
				(clearance 0)
			)
			(min_thickness 0.25)
			(keepout
				(tracks not_allowed)
				(vias allowed)
				(pads allowed)
				(copperpour not_allowed)
				(footprints allowed)
			)
			(placement
				(enabled no)
				(sheetname "")
			)
			(fill
				(thermal_gap 0.5)
				(thermal_bridge_width 0.5)
				(island_removal_mode 0)
			)
			(polygon
				(pts
					(xy 420.878 -147.574) (xy 420.878 -148.082) (xy 421.259 -148.082) (xy 421.259 -147.574)
				)
			)
		)
		(zone
			(layer "B.Cu")
			(hatch none 0.5)
			(connect_pads
				(clearance 0)
			)
			(min_thickness 0.25)
			(keepout
				(tracks allowed)
				(vias not_allowed)
				(pads allowed)
				(copperpour not_allowed)
				(footprints allowed)
			)
			(placement
				(enabled no)
				(sheetname "")
			)
			(fill
				(thermal_gap 0.5)
				(thermal_bridge_width 0.5)
				(island_removal_mode 0)
			)
			(polygon
				(pts
					(xy 421.259 -147.574) (xy 421.259 -148.082) (xy 420.878 -148.082) (xy 420.878 -147.574)
				)
			)
		)
	)
	(footprint ""
		(layer "B.Cu")
		(at 181.9656 -135.9662 180)
		(property "Reference" "C6L11"
			(at 0 0 0)
			(layer "B.SilkS")
			(hide yes)
			(effects
				(font
					(size 1.27 1.27)
				)
				(justify mirror)
			)
		)
		(property "Value" ""
			(at 0 0 0)
			(layer "B.Fab")
			(effects
				(font
					(size 1.27 1.27)
				)
				(justify mirror)
			)
		)
		(duplicate_pad_numbers_are_jumpers no)
		(fp_poly
			(pts
				(xy -0.3048 -0.1016) (xy -0.3048 0.9906) (xy 0.3048 0.9906) (xy 0.3048 -0.1016)
			)
			(stroke
				(width 0)
				(type default)
			)
			(fill no)
			(layer "B.CrtYd")
		)
		(fp_line
			(start 0.3048 0.9906)
			(end -0.3048 0.9906)
			(stroke
				(width 0.1)
				(type default)
			)
			(layer "B.Fab")
		)
		(fp_line
			(start 0.3048 -0.1016)
			(end 0.3048 0.9906)
			(stroke
				(width 0.1)
				(type default)
			)
			(layer "B.Fab")
		)
		(fp_line
			(start -0.3048 0.9906)
			(end -0.3048 -0.1016)
			(stroke
				(width 0.1)
				(type default)
			)
			(layer "B.Fab")
		)
		(fp_line
			(start -0.3048 -0.1016)
			(end 0.3048 -0.1016)
			(stroke
				(width 0.1)
				(type default)
			)
			(layer "B.Fab")
		)
		(pad "1" smd rect
			(at 0 0)
			(size 0.508 0.508)
			(layers "B.Cu" "B.Mask" "B.Paste")
			(net "VR_FET_SW_P12V_STBY_PVPP_KLM")
		)
		(pad "2" smd rect
			(at 0 0.889)
			(size 0.508 0.508)
			(layers "B.Cu" "B.Mask" "B.Paste")
			(net "GND")
		)
		(zone
			(layer "B.Cu")
			(hatch none 0.5)
			(connect_pads
				(clearance 0)
			)
			(min_thickness 0.25)
			(keepout
				(tracks not_allowed)
				(vias allowed)
				(pads allowed)
				(copperpour not_allowed)
				(footprints allowed)
			)
			(placement
				(enabled no)
				(sheetname "")
			)
			(fill
				(thermal_gap 0.5)
				(thermal_bridge_width 0.5)
				(island_removal_mode 0)
			)
			(polygon
				(pts
					(xy 181.7116 -136.6012) (xy 182.2196 -136.6012) (xy 182.2196 -136.2202) (xy 181.7116 -136.2202)
				)
			)
		)
		(zone
			(layer "B.Cu")
			(hatch none 0.5)
			(connect_pads
				(clearance 0)
			)
			(min_thickness 0.25)
			(keepout
				(tracks allowed)
				(vias not_allowed)
				(pads allowed)
				(copperpour not_allowed)
				(footprints allowed)
			)
			(placement
				(enabled no)
				(sheetname "")
			)
			(fill
				(thermal_gap 0.5)
				(thermal_bridge_width 0.5)
				(island_removal_mode 0)
			)
			(polygon
				(pts
					(xy 181.7116 -136.2202) (xy 182.2196 -136.2202) (xy 182.2196 -136.6012) (xy 181.7116 -136.6012)
				)
			)
		)
	)
	(footprint ""
		(layer "B.Cu")
		(at 464.33486 -41.18102)
		(property "Reference" "C9W14"
			(at -0.97536 0.76708 90)
			(unlocked yes)
			(layer "B.SilkS")
			(effects
				(font
					(size 0.4064 0.254)
					(thickness 0.1524)
				)
				(justify mirror)
			)
		)
		(property "Value" ""
			(at 0 0 0)
			(layer "B.Fab")
			(effects
				(font
					(size 1.27 1.27)
				)
				(justify mirror)
			)
		)
		(duplicate_pad_numbers_are_jumpers no)
		(fp_poly
			(pts
				(xy 0.4953 -0.2032) (xy -0.4953 -0.2032) (xy -0.4953 1.6002) (xy 0.4953 1.6002)
			)
			(stroke
				(width 0)
				(type default)
			)
			(fill no)
			(layer "B.CrtYd")
		)
		(fp_line
			(start -0.4953 -0.2032)
			(end -0.4953 1.6002)
			(stroke
				(width 0.1)
				(type default)
			)
			(layer "B.Fab")
		)
		(fp_line
			(start -0.4953 1.6002)
			(end 0.4953 1.6002)
			(stroke
				(width 0.1)
				(type default)
			)
			(layer "B.Fab")
		)
		(fp_line
			(start 0.4953 -0.2032)
			(end -0.4953 -0.2032)
			(stroke
				(width 0.1)
				(type default)
			)
			(layer "B.Fab")
		)
		(fp_line
			(start 0.4953 1.6002)
			(end 0.4953 -0.2032)
			(stroke
				(width 0.1)
				(type default)
			)
			(layer "B.Fab")
		)
		(pad "1" smd rect
			(at 0 0 180)
			(size 0.762 0.889)
			(layers "B.Cu" "B.Mask" "B.Paste")
			(net "P3V3_STBY")
		)
		(pad "2" smd rect
			(at 0 1.397 180)
			(size 0.762 0.889)
			(layers "B.Cu" "B.Mask" "B.Paste")
			(net "GND")
		)
		(zone
			(layer "B.Cu")
			(hatch none 0.5)
			(connect_pads
				(clearance 0)
			)
			(min_thickness 0.25)
			(keepout
				(tracks not_allowed)
				(vias allowed)
				(pads allowed)
				(copperpour not_allowed)
				(footprints allowed)
			)
			(placement
				(enabled no)
				(sheetname "")
			)
			(fill
				(thermal_gap 0.5)
				(thermal_bridge_width 0.5)
				(island_removal_mode 0)
			)
			(polygon
				(pts
					(xy 464.71586 -40.73652) (xy 463.95386 -40.73652) (xy 463.95386 -40.22852) (xy 464.71586 -40.22852)
				)
			)
		)
	)
)
